# TIMECARD (Time Appliance Project (Time Card)) — schematic netlist excerpt (pin names and nets, part order shuffled) for the footprints in the layout excerpt that follows; sources: Cadence DE-HDL packaged netlist, KiCad conversion of R4006-B0001-02_R01.brd

L11  FERRITEBEAD  26OHM 25%  pkg SMC_0603R_H030  page 30 : \1\ = XP3R3V ; \2\ = XP1R2V_VIN
TP23  TP_PIONT  pkg TP010CT020B030_PTH  page 25 : \1\ = FPGA_IN_LM75B_INT2_N
TP28  TP_PIONT  pkg TP010CT020B030_PTH  page 25 : \1\ = SMA1_SIG_IN_BF_EN_N

(kicad_pcb
	(version 20260206)
	(generator "pcbnew")
	(generator_version "10.0")
	(general
		(thickness 1.6)
		(legacy_teardrops no)
	)
	(paper "A4")
	(title_block
		(title "timecard-production-celestica-r4006 — R4006-B0001-02_R01.brd")
		(comment 1 "Time Appliance Project (Time Card) / footprints 444-446 of 1113")
	)
	(layers
		(0 "F.Cu" signal "TOP")
		(4 "In1.Cu" signal "L02_GND1")
		(6 "In2.Cu" signal "L03_SIG1")
		(8 "In3.Cu" signal "L04_GND2")
		(10 "In4.Cu" signal "L05_VCC1")
		(12 "In5.Cu" signal "L06_VCC2")
		(14 "In6.Cu" signal "L07_GND3")
		(16 "In7.Cu" signal "L08_SIG2")
		(18 "In8.Cu" signal "L09_GND4")
		(2 "B.Cu" signal "BOTTOM")
		(9 "F.Adhes" user "F.Adhesive")
		(11 "B.Adhes" user "B.Adhesive")
		(13 "F.Paste" user "Package Geometry/Pastemask Top")
		(15 "B.Paste" user "Package Geometry/Pastemask Bottom")
		(5 "F.SilkS" user "Ref Des/Silkscreen Top")
		(7 "B.SilkS" user "Ref Des/Silkscreen Bottom")
		(1 "F.Mask" user "Board Geometry/Soldermask Top")
		(3 "B.Mask" user "Board Geometry/Soldermask Bottom")
		(17 "Dwgs.User" user "User.Drawings")
		(19 "Cmts.User" user "User.Comments")
		(21 "Eco1.User" user "User.Eco1")
		(23 "Eco2.User" user "User.Eco2")
		(25 "Edge.Cuts" user "Board Geometry/Outline")
		(27 "Margin" user)
		(31 "F.CrtYd" user "Package Geometry/Place Bound Top")
		(29 "B.CrtYd" user "Package Geometry/Place Bound Bottom")
		(35 "F.Fab" user "Ref Des/Assembly Top")
		(33 "B.Fab" user "Ref Des/Assembly Bottom")
	)
	(footprint ""
		(layer "F.Cu")
		(at 93.4974 -78.7146)
		(property "Reference" "L11"
			(at -4.0259 -0.24003 0)
			(unlocked yes)
			(layer "F.SilkS")
			(effects
				(font
					(size 0.7874 0.5842)
					(thickness 0.1524)
				)
				(justify left)
			)
		)
		(property "Value" "VAL*"
			(at -0.9398 3.70967 0)
			(unlocked yes)
			(layer "F.Fab")
			(hide yes)
			(effects
				(font
					(size 0.7874 0.5842)
					(thickness 0.1524)
				)
				(justify left)
			)
		)
		(property "Tolerance" "TOL*"
			(at -0.9906 5.00507 0)
			(unlocked yes)
			(layer "Cmts.User")
			(hide yes)
			(effects
				(font
					(size 0.7874 0.5842)
					(thickness 0.1524)
				)
				(justify left)
			)
		)
		(property "User Part Number" "PARTNUM*"
			(at -2.54 2.46507 0)
			(unlocked yes)
			(layer "Cmts.User")
			(hide yes)
			(effects
				(font
					(size 0.7874 0.5842)
					(thickness 0.1524)
				)
				(justify left)
			)
		)
		(property "Device Type" "FERRITEBEAD-G191-10101-01,26OHA"
			(at -0.9906 1.22047 0)
			(unlocked yes)
			(layer "F.Fab")
			(hide yes)
			(effects
				(font
					(size 0.7874 0.5842)
					(thickness 0.1524)
				)
				(justify left)
			)
		)
		(duplicate_pad_numbers_are_jumpers no)
		(fp_line
			(start -1.3208 -0.7112)
			(end 1.3208 -0.7112)
			(stroke
				(width 0.1)
				(type default)
			)
			(layer "F.SilkS")
		)
		(fp_line
			(start -1.3208 0.7112)
			(end -1.3208 -0.7112)
			(stroke
				(width 0.1)
				(type default)
			)
			(layer "F.SilkS")
		)
		(fp_line
			(start 1.3208 -0.7112)
			(end 1.3208 0.7112)
			(stroke
				(width 0.1)
				(type default)
			)
			(layer "F.SilkS")
		)
		(fp_line
			(start 1.3208 0.7112)
			(end -1.3208 0.7112)
			(stroke
				(width 0.1)
				(type default)
			)
			(layer "F.SilkS")
		)
		(fp_rect
			(start -1.3208 -0.7112)
			(end 1.3208 0.7112)
			(stroke
				(width 0)
				(type default)
			)
			(fill no)
			(layer "F.CrtYd")
		)
		(fp_line
			(start -0.8128 -0.4572)
			(end 0.8128 -0.4572)
			(stroke
				(width 0.1)
				(type default)
			)
			(layer "F.Fab")
		)
		(fp_line
			(start -0.8128 0.4572)
			(end -0.8128 -0.4572)
			(stroke
				(width 0.1)
				(type default)
			)
			(layer "F.Fab")
		)
		(fp_line
			(start 0.8128 -0.4572)
			(end 0.8128 0.4572)
			(stroke
				(width 0.1)
				(type default)
			)
			(layer "F.Fab")
		)
		(fp_line
			(start 0.8128 0.4572)
			(end -0.8128 0.4572)
			(stroke
				(width 0.1)
				(type default)
			)
			(layer "F.Fab")
		)
		(pad "1" smd rect
			(at -0.6858 0)
			(size 0.762 0.8636)
			(layers "F.Cu" "F.Mask" "F.Paste")
			(net "XP3R3V")
		)
		(pad "2" smd rect
			(at 0.6858 0)
			(size 0.762 0.8636)
			(layers "F.Cu" "F.Mask" "F.Paste")
			(net "XP1R2V_VIN")
		)
		(zone
			(layer "F.Cu")
			(hatch none 0.5)
			(connect_pads
				(clearance 0)
			)
			(min_thickness 0.25)
			(keepout
				(tracks allowed)
				(vias not_allowed)
				(pads allowed)
				(copperpour not_allowed)
				(footprints allowed)
			)
			(placement
				(enabled no)
				(sheetname "")
			)
			(fill
				(thermal_gap 0.5)
				(thermal_bridge_width 0.5)
				(island_removal_mode 0)
			)
			(polygon
				(pts
					(xy 93.345 -79.1718) (xy 93.345 -78.2574) (xy 93.6498 -78.2574) (xy 93.6498 -79.1718)
				)
			)
		)
	)
	(footprint ""
		(layer "F.Cu")
		(at 51.2318 -83.2866 -90)
		(property "Reference" "TP23"
			(at -0.8382 0.01143 90)
			(unlocked yes)
			(layer "F.SilkS")
			(effects
				(font
					(size 0.7874 0.5842)
					(thickness 0.1524)
				)
				(justify left)
			)
		)
		(property "Value" ""
			(at 0 0 270)
			(layer "F.Fab")
			(effects
				(font
					(size 1.27 1.27)
				)
			)
		)
		(property "Device Type" "TP_PIONT-TP010CT020B030_PTH-TPA"
			(at -1.341882 0.996696 270)
			(unlocked yes)
			(layer "F.Fab")
			(hide yes)
			(effects
				(font
					(size 0.7874 0.5842)
					(thickness 0.000001)
				)
				(justify left)
			)
		)
		(duplicate_pad_numbers_are_jumpers no)
		(fp_poly
			(pts
				(arc
					(start 0 -0.889)
					(mid 0 0.889)
					(end 0 -0.889)
				)
			)
			(stroke
				(width 0)
				(type default)
			)
			(fill no)
			(layer "B.CrtYd")
		)
		(fp_poly
			(pts
				(arc
					(start 0 -0.889)
					(mid 0 0.889)
					(end 0 -0.889)
				)
			)
			(stroke
				(width 0)
				(type default)
			)
			(fill no)
			(layer "F.CrtYd")
		)
		(pad "1" thru_hole circle
			(at 0 0 270)
			(size 0.508 0.508)
			(drill 0.254)
			(layers "*.Cu" "*.Mask")
			(remove_unused_layers no)
			(net "FPGA_IN_LM75B_INT2_N")
			(clearance 0.1016)
			(padstack
				(mode front_inner_back)
				(layer "Inner"
					(shape circle)
					(size 0.508 0.508)
					(clearance 0.1016)
				)
				(layer "B.Cu"
					(shape circle)
					(size 0.762 0.762)
					(clearance -0.0254)
				)
			)
		)
	)
	(footprint ""
		(layer "F.Cu")
		(at 14.605 -57.531)
		(property "Reference" "TP28"
			(at 0.66675 2.8194 90)
			(unlocked yes)
			(layer "F.SilkS")
			(effects
				(font
					(size 0.635 0.4064)
					(thickness 0.1524)
				)
				(justify left)
			)
		)
		(property "Value" ""
			(at 0 0 0)
			(layer "F.Fab")
			(effects
				(font
					(size 1.27 1.27)
				)
			)
		)
		(property "Device Type" "TP_PIONT-TP010CT020B030_PTH-TPA"
			(at -1.341882 0.996696 0)
			(unlocked yes)
			(layer "F.Fab")
			(hide yes)
			(effects
				(font
					(size 0.7874 0.5842)
					(thickness 0.000001)
				)
				(justify left)
			)
		)
		(duplicate_pad_numbers_are_jumpers no)
		(fp_poly
			(pts
				(arc
					(start 0.889 0)
					(mid -0.889 0)
					(end 0.889 0)
				)
			)
			(stroke
				(width 0)
				(type default)
			)
			(fill no)
			(layer "B.CrtYd")
		)
		(fp_poly
			(pts
				(arc
					(start 0.889 0)
					(mid -0.889 0)
					(end 0.889 0)
				)
			)
			(stroke
				(width 0)
				(type default)
			)
			(fill no)
			(layer "F.CrtYd")
		)
		(pad "1" thru_hole circle
			(at 0 0)
			(size 0.508 0.508)
			(drill 0.254)
			(layers "*.Cu" "*.Mask")
			(remove_unused_layers no)
			(net "SMA1_SIG_IN_BF_EN_N")
			(clearance 0.1016)
			(padstack
				(mode front_inner_back)
				(layer "Inner"
					(shape circle)
					(size 0.508 0.508)
					(clearance 0.1016)
				)
				(layer "B.Cu"
					(shape circle)
					(size 0.762 0.762)
					(clearance -0.0254)
				)
			)
		)
	)
)
